(kicad_pcb
	(version 20240108)
	(generator "pcbnew")
	(generator_version "8.0")
	(general
		(thickness 1.62)
		(legacy_teardrops no)
	)
	(paper "A4")
	(title_block
		(title "Jetson Orin Baseboard")
		(date "2025-03-12")
		(rev "1.3.4")
		(company "Antmicro Ltd")
		(comment 1 "www.antmicro.com")
		(comment 9 "footprints 575-578 of 677")
	)
	(layers
		(0 "F.Cu" signal)
		(1 "In1.Cu" signal)
		(2 "In2.Cu" signal)
		(3 "In3.Cu" signal)
		(4 "In4.Cu" jumper)
		(5 "In5.Cu" signal)
		(6 "In6.Cu" signal)
		(31 "B.Cu" signal)
		(32 "B.Adhes" user "B.Adhesive")
		(33 "F.Adhes" user "F.Adhesive")
		(34 "B.Paste" user)
		(35 "F.Paste" user)
		(36 "B.SilkS" user "B.Silkscreen")
		(37 "F.SilkS" user "F.Silkscreen")
		(38 "B.Mask" user)
		(39 "F.Mask" user)
		(40 "Dwgs.User" user "User.Drawings")
		(41 "Cmts.User" user "User.Comments")
		(42 "Eco1.User" user "User.Eco1")
		(43 "Eco2.User" user "User.Eco2")
		(44 "Edge.Cuts" user)
		(45 "Margin" user)
		(46 "B.CrtYd" user "B.Courtyard")
		(47 "F.CrtYd" user "F.Courtyard")
		(48 "B.Fab" user)
		(49 "F.Fab" user)
	)
	(footprint "antmicro-footprints:R_0402_1005Metric"
		(layer "B.Cu")
		(at 96.5 98.43)
		(descr "Resistor SMD 0402")
		(tags "resistor SMD 0402")
		(property "Reference" "R168"
			(at 1.15 -0.43 180)
			(layer "B.SilkS")
			(effects
				(font
					(size 0.7 0.7)
					(thickness 0.15)
				)
				(justify left bottom mirror)
			)
		)
		(property "Value" "R_0R_0402"
			(at 0 -1.4 180)
			(layer "B.Fab")
			(effects
				(font
					(size 0.7 0.7)
					(thickness 0.15)
				)
				(justify left bottom mirror)
			)
		)
		(property "Footprint" "antmicro-footprints:R_0402_1005Metric"
			(at 0 0 0)
			(layer "F.Fab")
			(hide yes)
			(effects
				(font
					(size 1.27 1.27)
					(thickness 0.15)
				)
			)
		)
		(property "Datasheet" "https://industrial.panasonic.com/cdbs/www-data/pdf/RDA0000/AOA0000C301.pdf"
			(at 0 0 0)
			(layer "F.Fab")
			(hide yes)
			(effects
				(font
					(size 1.27 1.27)
					(thickness 0.15)
				)
			)
		)
		(property "Author" "Antmicro"
			(at 0 0 0)
			(layer "B.Fab")
			(hide yes)
			(effects
				(font
					(size 1 1)
					(thickness 0.15)
				)
				(justify mirror)
			)
		)
		(property "Current" "1A"
			(at 0 0 0)
			(layer "B.Fab")
			(hide yes)
			(effects
				(font
					(size 1 1)
					(thickness 0.15)
				)
				(justify mirror)
			)
		)
		(property "License" "Apache-2.0"
			(at 0 0 0)
			(layer "B.Fab")
			(hide yes)
			(effects
				(font
					(size 1 1)
					(thickness 0.15)
				)
				(justify mirror)
			)
		)
		(property "MPN" "ERJ2GE0R00X"
			(at 0 0 0)
			(layer "B.Fab")
			(hide yes)
			(effects
				(font
					(size 1 1)
					(thickness 0.15)
				)
				(justify mirror)
			)
		)
		(property "Manufacturer" "Panasonic"
			(at 0 0 0)
			(layer "B.Fab")
			(hide yes)
			(effects
				(font
					(size 1 1)
					(thickness 0.15)
				)
				(justify mirror)
			)
		)
		(property "Tolerance" ""
			(at 0 0 0)
			(layer "B.Fab")
			(hide yes)
			(effects
				(font
					(size 1 1)
					(thickness 0.15)
				)
				(justify mirror)
			)
		)
		(property "Val" "0R"
			(at 0 0 0)
			(layer "B.Fab")
			(hide yes)
			(effects
				(font
					(size 1 1)
					(thickness 0.15)
				)
				(justify mirror)
			)
		)
		(sheetname "CSI")
		(sheetfile "csi.kicad_sch")
		(attr smd)
		(fp_rect
			(start -0.925 0.47)
			(end 0.925 -0.47)
			(stroke
				(width 0.05)
				(type default)
			)
			(fill none)
			(layer "B.CrtYd")
		)
		(fp_rect
			(start -0.5 0.25)
			(end 0.5 -0.25)
			(stroke
				(width 0.15)
				(type solid)
			)
			(fill none)
			(layer "B.Fab")
		)
		(fp_text user "License: Apache-2.0"
			(at -0.95 -5.169 180)
			(layer "B.Fab")
			(hide yes)
			(effects
				(font
					(size 0.7 0.7)
					(thickness 0.15)
				)
				(justify left bottom mirror)
			)
		)
		(fp_text user "${REFERENCE}"
			(at -0.95 -3.168 180)
			(layer "B.Fab")
			(hide yes)
			(effects
				(font
					(size 0.7 0.7)
					(thickness 0.15)
				)
				(justify left bottom mirror)
			)
		)
		(fp_text user "Author: Antmicro"
			(at -0.95 -4.169 180)
			(layer "B.Fab")
			(hide yes)
			(effects
				(font
					(size 0.7 0.7)
					(thickness 0.15)
				)
				(justify left bottom mirror)
			)
		)
		(pad "1" smd roundrect
			(at -0.48 0)
			(size 0.59 0.64)
			(layers "B.Cu" "B.Paste" "B.Mask")
			(roundrect_rratio 0.25)
			(net 1 "GND")
			(pintype "passive")
		)
		(pad "2" smd roundrect
			(at 0.48 0)
			(size 0.59 0.64)
			(layers "B.Cu" "B.Paste" "B.Mask")
			(roundrect_rratio 0.25)
			(net 325 "/CSI/I2C_MUX_A0")
			(pintype "passive")
		)
	)
	(footprint "antmicro-footprints:R_0402_1005Metric"
		(layer "B.Cu")
		(at 100.175 104.625)
		(descr "Resistor SMD 0402")
		(tags "resistor SMD 0402")
		(property "Reference" "R171"
			(at 1.135 1.325 180)
			(layer "B.SilkS")
			(effects
				(font
					(size 0.7 0.7)
					(thickness 0.15)
				)
				(justify left bottom mirror)
			)
		)
		(property "Value" "R_0R_0402"
			(at 0 -1.4 180)
			(layer "B.Fab")
			(effects
				(font
					(size 0.7 0.7)
					(thickness 0.15)
				)
				(justify left bottom mirror)
			)
		)
		(property "Footprint" "antmicro-footprints:R_0402_1005Metric"
			(at 0 0 0)
			(layer "F.Fab")
			(hide yes)
			(effects
				(font
					(size 1.27 1.27)
					(thickness 0.15)
				)
			)
		)
		(property "Datasheet" "https://industrial.panasonic.com/cdbs/www-data/pdf/RDA0000/AOA0000C301.pdf"
			(at 0 0 0)
			(layer "F.Fab")
			(hide yes)
			(effects
				(font
					(size 1.27 1.27)
					(thickness 0.15)
				)
			)
		)
		(property "Author" "Antmicro"
			(at 0 0 0)
			(layer "B.Fab")
			(hide yes)
			(effects
				(font
					(size 1 1)
					(thickness 0.15)
				)
				(justify mirror)
			)
		)
		(property "Current" "1A"
			(at 0 0 0)
			(layer "B.Fab")
			(hide yes)
			(effects
				(font
					(size 1 1)
					(thickness 0.15)
				)
				(justify mirror)
			)
		)
		(property "License" "Apache-2.0"
			(at 0 0 0)
			(layer "B.Fab")
			(hide yes)
			(effects
				(font
					(size 1 1)
					(thickness 0.15)
				)
				(justify mirror)
			)
		)
		(property "MPN" "ERJ2GE0R00X"
			(at 0 0 0)
			(layer "B.Fab")
			(hide yes)
			(effects
				(font
					(size 1 1)
					(thickness 0.15)
				)
				(justify mirror)
			)
		)
		(property "Manufacturer" "Panasonic"
			(at 0 0 0)
			(layer "B.Fab")
			(hide yes)
			(effects
				(font
					(size 1 1)
					(thickness 0.15)
				)
				(justify mirror)
			)
		)
		(property "Tolerance" ""
			(at 0 0 0)
			(layer "B.Fab")
			(hide yes)
			(effects
				(font
					(size 1 1)
					(thickness 0.15)
				)
				(justify mirror)
			)
		)
		(property "Val" "0R"
			(at 0 0 0)
			(layer "B.Fab")
			(hide yes)
			(effects
				(font
					(size 1 1)
					(thickness 0.15)
				)
				(justify mirror)
			)
		)
		(sheetname "CSI")
		(sheetfile "csi.kicad_sch")
		(attr smd exclude_from_pos_files exclude_from_bom dnp)
		(fp_rect
			(start -0.925 0.47)
			(end 0.925 -0.47)
			(stroke
				(width 0.05)
				(type default)
			)
			(fill none)
			(layer "B.CrtYd")
		)
		(fp_rect
			(start -0.5 0.25)
			(end 0.5 -0.25)
			(stroke
				(width 0.15)
				(type solid)
			)
			(fill none)
			(layer "B.Fab")
		)
		(fp_text user "Author: Antmicro"
			(at -0.95 -4.169 180)
			(layer "B.Fab")
			(hide yes)
			(effects
				(font
					(size 0.7 0.7)
					(thickness 0.15)
				)
				(justify left bottom mirror)
			)
		)
		(fp_text user "${REFERENCE}"
			(at -0.95 -3.168 180)
			(layer "B.Fab")
			(hide yes)
			(effects
				(font
					(size 0.7 0.7)
					(thickness 0.15)
				)
				(justify left bottom mirror)
			)
		)
		(fp_text user "License: Apache-2.0"
			(at -0.95 -5.169 180)
			(layer "B.Fab")
			(hide yes)
			(effects
				(font
					(size 0.7 0.7)
					(thickness 0.15)
				)
				(justify left bottom mirror)
			)
		)
		(pad "1" smd roundrect
			(at -0.48 0)
			(size 0.59 0.64)
			(layers "B.Cu" "B.Paste" "B.Mask")
			(roundrect_rratio 0.25)
			(net 321 "/CSI/CSIA_I2C_VCC")
			(pintype "passive")
		)
		(pad "2" smd roundrect
			(at 0.48 0)
			(size 0.59 0.64)
			(layers "B.Cu" "B.Paste" "B.Mask")
			(roundrect_rratio 0.25)
			(net 112 "+1V8")
			(pintype "passive")
		)
	)
	(footprint "antmicro-footprints:R_0402_1005Metric"
		(layer "B.Cu")
		(at 53.78 83.2)
		(descr "Resistor SMD 0402")
		(tags "resistor SMD 0402")
		(property "Reference" "R284"
			(at -3.605 -0.525 0)
			(layer "B.SilkS")
			(effects
				(font
					(size 0.7 0.7)
					(thickness 0.15)
				)
				(justify right top mirror)
			)
		)
		(property "Value" "R_560R_0402"
			(at -1.011843 -1.772046 0)
			(layer "B.Fab")
			(effects
				(font
					(size 0.7 0.7)
					(thickness 0.15)
				)
				(justify right top mirror)
			)
		)
		(property "Footprint" "antmicro-footprints:R_0402_1005Metric"
			(at 0 0 0)
			(layer "B.Fab")
			(hide yes)
			(effects
				(font
					(size 1.27 1.27)
					(thickness 0.15)
				)
				(justify mirror)
			)
		)
		(property "Datasheet" "https://www.bourns.com/docs/product-datasheets/cr.pdf"
			(at 0 0 0)
			(layer "B.Fab")
			(hide yes)
			(effects
				(font
					(size 1.27 1.27)
					(thickness 0.15)
				)
				(justify mirror)
			)
		)
		(property "Description" "SMD Chip Resistor, 560 ohm, ± 1%, 100 mW, 0402 [1005 Metric], Thick Film, Precision"
			(at 0 0 0)
			(layer "B.Fab")
			(hide yes)
			(effects
				(font
					(size 1.27 1.27)
					(thickness 0.15)
				)
				(justify mirror)
			)
		)
		(property "MPN" "CR0402-FX-5600GLF"
			(at 0 0 180)
			(unlocked yes)
			(layer "B.Fab")
			(hide yes)
			(effects
				(font
					(size 1 1)
					(thickness 0.15)
				)
				(justify mirror)
			)
		)
		(property "Manufacturer" "Bourns"
			(at 0 0 180)
			(unlocked yes)
			(layer "B.Fab")
			(hide yes)
			(effects
				(font
					(size 1 1)
					(thickness 0.15)
				)
				(justify mirror)
			)
		)
		(property "License" "Apache-2.0"
			(at 0 0 180)
			(unlocked yes)
			(layer "B.Fab")
			(hide yes)
			(effects
				(font
					(size 1 1)
					(thickness 0.15)
				)
				(justify mirror)
			)
		)
		(property "Author" "Antmicro"
			(at 0 0 180)
			(unlocked yes)
			(layer "B.Fab")
			(hide yes)
			(effects
				(font
					(size 1 1)
					(thickness 0.15)
				)
				(justify mirror)
			)
		)
		(property "Val" "560R"
			(at 0 0 180)
			(unlocked yes)
			(layer "B.Fab")
			(hide yes)
			(effects
				(font
					(size 1 1)
					(thickness 0.15)
				)
				(justify mirror)
			)
		)
		(property "Tolerance" "1%"
			(at 0 0 180)
			(unlocked yes)
			(layer "B.Fab")
			(hide yes)
			(effects
				(font
					(size 1 1)
					(thickness 0.15)
				)
				(justify mirror)
			)
		)
		(sheetname "Supply")
		(sheetfile "supply.kicad_sch")
		(attr smd)
		(fp_poly
			(pts
				(xy -0.925 0.47) (xy 0.925 0.47) (xy 0.925 -0.47) (xy -0.925 -0.47)
			)
			(stroke
				(width 0.05)
				(type default)
			)
			(fill none)
			(layer "B.CrtYd")
		)
		(fp_poly
			(pts
				(xy -0.5 0.25) (xy 0.5 0.25) (xy 0.5 -0.25) (xy -0.5 -0.25)
			)
			(stroke
				(width 0.15)
				(type solid)
			)
			(fill none)
			(layer "B.Fab")
		)
		(fp_text user "License: Apache-2.0"
			(at -0.949999 -5.169 0)
			(layer "B.Fab")
			(hide yes)
			(effects
				(font
					(size 0.7 0.7)
					(thickness 0.15)
				)
				(justify right top mirror)
			)
		)
		(fp_text user "${REFERENCE}"
			(at -0.95 -3.168 0)
			(layer "B.Fab")
			(hide yes)
			(effects
				(font
					(size 0.7 0.7)
					(thickness 0.15)
				)
				(justify right top mirror)
			)
		)
		(fp_text user "Author: Antmicro"
			(at -0.95 -4.169 0)
			(layer "B.Fab")
			(hide yes)
			(effects
				(font
					(size 0.7 0.7)
					(thickness 0.15)
				)
				(justify right top mirror)
			)
		)
		(pad "1" smd roundrect
			(at -0.48 0)
			(size 0.59 0.64)
			(layers "B.Cu" "B.Paste" "B.Mask")
			(roundrect_rratio 0.25)
			(net 1 "GND")
			(pintype "passive")
		)
		(pad "2" smd roundrect
			(at 0.48 0)
			(size 0.59 0.64)
			(layers "B.Cu" "B.Paste" "B.Mask")
			(roundrect_rratio 0.25)
			(net 791 "Net-(U48-ILIM)")
			(pintype "passive")
		)
	)
	(footprint "antmicro-footprints:LED_0603_1608Metric_G"
		(layer "B.Cu")
		(at 144.5 114 180)
		(descr "LED SMD 0603 Green")
		(tags "LED SMD 0603 Green")
		(property "Reference" "D18"
			(at -0.55 -1.475 0)
			(layer "B.SilkS")
			(effects
				(font
					(size 0.7 0.7)
					(thickness 0.15)
				)
				(justify left bottom mirror)
			)
		)
		(property "Value" "LED_G_0603_LTST-C190GKT"
			(at -0.001 -1.599 0)
			(layer "B.Fab")
			(effects
				(font
					(size 0.7 0.7)
					(thickness 0.15)
				)
				(justify left bottom mirror)
			)
		)
		(property "Footprint" "antmicro-footprints:LED_0603_1608Metric_G"
			(at 0 0 180)
			(layer "F.Fab")
			(hide yes)
			(effects
				(font
					(size 1.27 1.27)
					(thickness 0.15)
				)
			)
		)
		(property "Datasheet" "https://media.digikey.com/pdf/Data%20Sheets/Lite-On%20PDFs/LTST-C190GKT.pdf"
			(at 0 0 180)
			(layer "F.Fab")
			(hide yes)
			(effects
				(font
					(size 1.27 1.27)
					(thickness 0.15)
				)
			)
		)
		(property "Author" "Antmicro"
			(at 289 228 0)
			(layer "B.Fab")
			(hide yes)
			(effects
				(font
					(size 1 1)
					(thickness 0.15)
				)
				(justify mirror)
			)
		)
		(property "Color" "Green"
			(at 289 228 0)
			(layer "B.Fab")
			(hide yes)
			(effects
				(font
					(size 1 1)
					(thickness 0.15)
				)
				(justify mirror)
			)
		)
		(property "License" "Apache-2.0"
			(at 289 228 0)
			(layer "B.Fab")
			(hide yes)
			(effects
				(font
					(size 1 1)
					(thickness 0.15)
				)
				(justify mirror)
			)
		)
		(property "MPN" "LTST-C190GKT"
			(at 289 228 0)
			(layer "B.Fab")
			(hide yes)
			(effects
				(font
					(size 1 1)
					(thickness 0.15)
				)
				(justify mirror)
			)
		)
		(property "Manufacturer" "Lite-On"
			(at 289 228 0)
			(layer "B.Fab")
			(hide yes)
			(effects
				(font
					(size 1 1)
					(thickness 0.15)
				)
				(justify mirror)
			)
		)
		(sheetname "CSI")
		(sheetfile "csi.kicad_sch")
		(attr smd)
		(fp_line
			(start 0.24 -0.001)
			(end 0.105328 -0.001008)
			(stroke
				(width 0.1)
				(type solid)
			)
			(layer "B.SilkS")
		)
		(fp_line
			(start 0.105328 0.198992)
			(end 0.105328 -0.201008)
			(stroke
				(width 0.1)
				(type solid)
			)
			(layer "B.SilkS")
		)
		(fp_line
			(start 0.105328 0.198992)
			(end -0.094672 -0.001008)
			(stroke
				(width 0.1)
				(type solid)
			)
			(layer "B.SilkS")
		)
		(fp_line
			(start -0.094672 0.198992)
			(end -0.094672 -0.201008)
			(stroke
				(width 0.1)
				(type solid)
			)
			(layer "B.SilkS")
		)
		(fp_line
			(start -0.094672 -0.001008)
			(end 0.105328 -0.201008)
			(stroke
				(width 0.1)
				(type solid)
			)
			(layer "B.SilkS")
		)
		(fp_line
			(start -0.22 0.35)
			(end 0.22 0.35)
			(stroke
				(width 0.15)
				(type solid)
			)
			(layer "B.SilkS")
		)
		(fp_line
			(start -0.22 -0.35)
			(end 0.22 -0.35)
			(stroke
				(width 0.15)
				(type solid)
			)
			(layer "B.SilkS")
		)
		(fp_line
			(start -0.24 -0.001008)
			(end -0.094672 -0.001008)
			(stroke
				(width 0.1)
				(type solid)
			)
			(layer "B.SilkS")
		)
		(fp_line
			(start -1.18 -0.321)
			(end -1.18 0.319)
			(stroke
				(width 0.15)
				(type solid)
			)
			(layer "B.SilkS")
		)
		(fp_rect
			(start 1.25 -0.65)
			(end -1.25 0.65)
			(stroke
				(width 0.05)
				(type solid)
			)
			(fill none)
			(layer "B.CrtYd")
		)
		(fp_line
			(start 0.201 0.202)
			(end 0.201 0)
			(stroke
				(width 0.15)
				(type solid)
			)
			(layer "B.Fab")
		)
		(fp_line
			(start 0.201 0)
			(end 0.599 0)
			(stroke
				(width 0.15)
				(type solid)
			)
			(layer "B.Fab")
		)
		(fp_line
			(start 0.201 0)
			(end 0.201 -0.2)
			(stroke
				(width 0.15)
				(type solid)
			)
			(layer "B.Fab")
		)
		(fp_line
			(start 0.201 -0.2)
			(end -0.101 0)
			(stroke
				(width 0.15)
				(type solid)
			)
			(layer "B.Fab")
		)
		(fp_line
			(start -0.101 0)
			(end 0.201 0.202)
			(stroke
				(width 0.15)
				(type solid)
			)
			(layer "B.Fab")
		)
		(fp_line
			(start -0.199 -0.1)
			(end -0.199 0.202)
			(stroke
				(width 0.15)
				(type solid)
			)
			(layer "B.Fab")
		)
		(fp_line
			(start -0.199 -0.1)
			(end -0.199 -0.2)
			(stroke
				(width 0.15)
				(type solid)
			)
			(layer "B.Fab")
		)
		(fp_line
			(start -0.597 0)
			(end -0.199 0)
			(stroke
				(width 0.15)
				(type solid)
			)
			(layer "B.Fab")
		)
		(fp_rect
			(start 0.848 -0.4)
			(end -0.85 0.402)
			(stroke
				(width 0.15)
				(type solid)
			)
			(fill none)
			(layer "B.Fab")
		)
		(fp_text user "License: Apache-2.0"
			(at -1.4224 -3.599 0)
			(layer "B.Fab")
			(hide yes)
			(effects
				(font
					(size 0.7 0.7)
					(thickness 0.15)
				)
				(justify left bottom mirror)
			)
		)
		(fp_text user "Author: Antmicro"
			(at -1.4224 -4.799 0)
			(layer "B.Fab")
			(hide yes)
			(effects
				(font
					(size 0.7 0.7)
					(thickness 0.15)
				)
				(justify left bottom mirror)
			)
		)
		(fp_text user "${REFERENCE}"
			(at -1.4224 -5.999 0)
			(layer "B.Fab")
			(hide yes)
			(effects
				(font
					(size 0.7 0.7)
					(thickness 0.15)
				)
				(justify left bottom mirror)
			)
		)
		(pad "1" smd roundrect
			(at -0.7 0)
			(size 0.8 1)
			(layers "B.Cu" "B.Paste" "B.Mask")
			(roundrect_rratio 0.2)
			(net 1 "GND")
			(pinfunction "C")
			(pintype "passive")
		)
		(pad "2" smd roundrect
			(at 0.7 0)
			(size 0.8 1)
			(layers "B.Cu" "B.Paste" "B.Mask")
			(roundrect_rratio 0.2)
			(net 155 "Net-(D18-A)")
			(pinfunction "A")
			(pintype "passive")
		)
	)
)
